(kicad_pcb
	(version 20241229)
	(generator "pcbnew")
	(generator_version "9.0")
	(general
		(thickness 1.6642)
		(legacy_teardrops no)
	)
	(paper "A3")
	(title_block
		(title "PolarFire SoM")
		(date "2025-07-22")
		(rev "1.1.4")
		(company "Antmicro Ltd")
		(comment 1 "www.antmicro.com")
		(comment 9 "footprints 363-366 of 470")
	)
	(layers
		(0 "F.Cu" mixed)
		(4 "In1.Cu" power)
		(6 "In2.Cu" signal)
		(8 "In3.Cu" power)
		(10 "In4.Cu" signal)
		(12 "In5.Cu" power)
		(14 "In6.Cu" power)
		(16 "In7.Cu" signal)
		(18 "In8.Cu" power)
		(20 "In9.Cu" signal)
		(22 "In10.Cu" power)
		(24 "In11.Cu" signal)
		(26 "In12.Cu" signal)
		(2 "B.Cu" mixed)
		(9 "F.Adhes" user "F.Adhesive")
		(11 "B.Adhes" user "B.Adhesive")
		(13 "F.Paste" user)
		(15 "B.Paste" user)
		(5 "F.SilkS" user "F.Silkscreen")
		(7 "B.SilkS" user "B.Silkscreen")
		(1 "F.Mask" user)
		(3 "B.Mask" user)
		(17 "Dwgs.User" user "User.Drawings")
		(19 "Cmts.User" user "User.Comments")
		(21 "Eco1.User" user "User.Eco1")
		(23 "Eco2.User" user "User.Eco2")
		(25 "Edge.Cuts" user)
		(27 "Margin" user)
		(31 "F.CrtYd" user "F.Courtyard")
		(29 "B.CrtYd" user "B.Courtyard")
		(35 "F.Fab" user)
		(33 "B.Fab" user)
	)
	(footprint "antmicro-footprints:C_Array_0508_1220Metric"
		(layer "B.Cu")
		(at 196.34 142.85 180)
		(property "Reference" "C172"
			(at 1.18 1.59 90)
			(layer "B.SilkS")
			(effects
				(font
					(size 0.7 0.7)
					(thickness 0.15)
				)
				(justify left bottom mirror)
			)
		)
		(property "Value" "C_4x100nF_0508_1220Metric_array"
			(at 0 -2.8 0)
			(layer "B.Fab")
			(hide yes)
			(effects
				(font
					(size 0.7 0.7)
					(thickness 0.15)
				)
				(justify left bottom mirror)
			)
		)
		(property "Datasheet" "https://spicat.kyocera-avx.com/product/mlcc/chartview/W2A4YC104MAT2A/"
			(at 0 0 180)
			(layer "F.Fab")
			(hide yes)
			(effects
				(font
					(size 1.27 1.27)
					(thickness 0.15)
				)
			)
		)
		(property "Description" "4x0.1µF isolated capacitor array 16 V X7R 0508 (1220 Metric)"
			(at 0 0 180)
			(layer "F.Fab")
			(hide yes)
			(effects
				(font
					(size 1.27 1.27)
					(thickness 0.15)
				)
			)
		)
		(property "Author" "Antmicro"
			(at 392.68 285.7 0)
			(layer "B.Fab")
			(hide yes)
			(effects
				(font
					(size 1 1)
					(thickness 0.15)
				)
				(justify mirror)
			)
		)
		(property "Dielectric" "X7R"
			(at 392.68 285.7 0)
			(layer "B.Fab")
			(hide yes)
			(effects
				(font
					(size 1 1)
					(thickness 0.15)
				)
				(justify mirror)
			)
		)
		(property "License" "Apache-2.0"
			(at 392.68 285.7 0)
			(layer "B.Fab")
			(hide yes)
			(effects
				(font
					(size 1 1)
					(thickness 0.15)
				)
				(justify mirror)
			)
		)
		(property "MPN" "W2A4YC104MAT2A"
			(at 392.68 285.7 0)
			(layer "B.Fab")
			(hide yes)
			(effects
				(font
					(size 1 1)
					(thickness 0.15)
				)
				(justify mirror)
			)
		)
		(property "Manufacturer" "KYOCERA AVX"
			(at 392.68 285.7 0)
			(layer "B.Fab")
			(hide yes)
			(effects
				(font
					(size 1 1)
					(thickness 0.15)
				)
				(justify mirror)
			)
		)
		(property "Val" "4x100nF"
			(at 392.68 285.7 0)
			(layer "B.Fab")
			(hide yes)
			(effects
				(font
					(size 1 1)
					(thickness 0.15)
				)
				(justify mirror)
			)
		)
		(property "Voltage" "16V"
			(at 392.68 285.7 0)
			(layer "B.Fab")
			(hide yes)
			(effects
				(font
					(size 1 1)
					(thickness 0.15)
				)
				(justify mirror)
			)
		)
		(sheetname "/PCIe/")
		(sheetfile "pcie.kicad_sch")
		(attr smd)
		(fp_circle
			(center -1.21 0.75)
			(end -1.16 0.75)
			(stroke
				(width 0.15)
				(type solid)
			)
			(fill yes)
			(layer "B.SilkS")
		)
		(fp_rect
			(start -1.09 1.2)
			(end 1.09 -1.2)
			(stroke
				(width 0.05)
				(type solid)
			)
			(fill no)
			(layer "B.CrtYd")
		)
		(fp_line
			(start 0.65 1.05)
			(end 0.65 -1.05)
			(stroke
				(width 0.15)
				(type solid)
			)
			(layer "B.Fab")
		)
		(fp_line
			(start 0.65 -1.05)
			(end -0.65 -1.05)
			(stroke
				(width 0.15)
				(type solid)
			)
			(layer "B.Fab")
		)
		(fp_line
			(start -0.65 1.05)
			(end 0.65 1.05)
			(stroke
				(width 0.15)
				(type solid)
			)
			(layer "B.Fab")
		)
		(fp_line
			(start -0.65 -1.05)
			(end -0.65 1.05)
			(stroke
				(width 0.15)
				(type solid)
			)
			(layer "B.Fab")
		)
		(fp_text user "Author: Antmicro"
			(at -1.26 -7.2 0)
			(layer "B.Fab")
			(effects
				(font
					(size 0.7 0.7)
					(thickness 0.15)
				)
				(justify left bottom mirror)
			)
		)
		(fp_text user "${REFERENCE}"
			(at -1.26 -6 0)
			(layer "B.Fab")
			(effects
				(font
					(size 0.7 0.7)
					(thickness 0.15)
				)
				(justify left bottom mirror)
			)
		)
		(fp_text user "License: Apache-2.0"
			(at -1.26 -4.8 0)
			(layer "B.Fab")
			(effects
				(font
					(size 0.7 0.7)
					(thickness 0.15)
				)
				(justify left bottom mirror)
			)
		)
		(pad "1" smd roundrect
			(at -0.66 0.75 270)
			(size 0.3 0.56)
			(layers "B.Cu" "B.Mask" "B.Paste")
			(roundrect_rratio 0.25)
			(net 37 "/Bottom Connector/PCIE.TXD2_P")
			(pinfunction "R1.1")
			(pintype "passive")
		)
		(pad "2" smd roundrect
			(at -0.66 0.25 270)
			(size 0.3 0.56)
			(layers "B.Cu" "B.Mask" "B.Paste")
			(roundrect_rratio 0.25)
			(net 38 "/Bottom Connector/PCIE.TXD2_N")
			(pinfunction "R2.1")
			(pintype "passive")
		)
		(pad "3" smd roundrect
			(at -0.66 -0.25 270)
			(size 0.3 0.56)
			(layers "B.Cu" "B.Mask" "B.Paste")
			(roundrect_rratio 0.25)
			(net 39 "/Bottom Connector/PCIE.TXD3_P")
			(pinfunction "R3.1")
			(pintype "passive")
		)
		(pad "4" smd roundrect
			(at -0.66 -0.75 270)
			(size 0.3 0.56)
			(layers "B.Cu" "B.Mask" "B.Paste")
			(roundrect_rratio 0.25)
			(net 40 "/Bottom Connector/PCIE.TXD3_N")
			(pinfunction "R4.1")
			(pintype "passive")
		)
		(pad "5" smd roundrect
			(at 0.66 -0.75 270)
			(size 0.3 0.56)
			(layers "B.Cu" "B.Mask" "B.Paste")
			(roundrect_rratio 0.25)
			(net 66 "/PCIe/XCVR_TX3_N")
			(pinfunction "R4.2")
			(pintype "passive")
		)
		(pad "6" smd roundrect
			(at 0.66 -0.25 270)
			(size 0.3 0.56)
			(layers "B.Cu" "B.Mask" "B.Paste")
			(roundrect_rratio 0.25)
			(net 91 "/PCIe/XCVR_TX3_P")
			(pinfunction "R3.2")
			(pintype "passive")
		)
		(pad "7" smd roundrect
			(at 0.66 0.25 270)
			(size 0.3 0.56)
			(layers "B.Cu" "B.Mask" "B.Paste")
			(roundrect_rratio 0.25)
			(net 93 "/PCIe/XCVR_TX2_N")
			(pinfunction "R2.2")
			(pintype "passive")
		)
		(pad "8" smd roundrect
			(at 0.66 0.75 270)
			(size 0.3 0.56)
			(layers "B.Cu" "B.Mask" "B.Paste")
			(roundrect_rratio 0.25)
			(net 95 "/PCIe/XCVR_TX2_P")
			(pinfunction "R1.2")
			(pintype "passive")
		)
	)
	(footprint "antmicro-footprints:C_0402_1005Metric"
		(layer "B.Cu")
		(at 219.911 119.7234)
		(descr "Capacitor SMD 0402")
		(tags "capacitor SMD 0402")
		(property "Reference" "C192"
			(at 6.539 4.2266 0)
			(layer "B.SilkS")
			(effects
				(font
					(size 0.7 0.7)
					(thickness 0.15)
				)
				(justify right bottom mirror)
			)
		)
		(property "Value" "C_10u_0402"
			(at -1.022927 -2.155213 0)
			(layer "B.Fab")
			(hide yes)
			(effects
				(font
					(size 0.7 0.7)
					(thickness 0.15)
				)
				(justify right bottom mirror)
			)
		)
		(property "Datasheet" "https://www.yageo.com/en/Chart/Download/pdf/CC0402MRX5R5BB106"
			(at 0 0 0)
			(layer "F.Fab")
			(hide yes)
			(effects
				(font
					(size 1.27 1.27)
					(thickness 0.15)
				)
			)
		)
		(property "Description" "SMD Multilayer Ceramic Capacitor, 10 µF, 6.3 V, 0402 [1005 Metric], ± 20%, X5R, CC Series"
			(at 0 0 0)
			(layer "F.Fab")
			(hide yes)
			(effects
				(font
					(size 1.27 1.27)
					(thickness 0.15)
				)
			)
		)
		(property "Author" "Antmicro"
			(at 0 0 0)
			(layer "B.Fab")
			(hide yes)
			(effects
				(font
					(size 1 1)
					(thickness 0.15)
				)
				(justify mirror)
			)
		)
		(property "Dielectric" ""
			(at 0 0 0)
			(layer "B.Fab")
			(hide yes)
			(effects
				(font
					(size 1 1)
					(thickness 0.15)
				)
				(justify mirror)
			)
		)
		(property "License" "Apache-2.0"
			(at 0 0 0)
			(layer "B.Fab")
			(hide yes)
			(effects
				(font
					(size 1 1)
					(thickness 0.15)
				)
				(justify mirror)
			)
		)
		(property "MPN" "CC0402MRX5R5BB106"
			(at 0 0 0)
			(layer "B.Fab")
			(hide yes)
			(effects
				(font
					(size 1 1)
					(thickness 0.15)
				)
				(justify mirror)
			)
		)
		(property "Manufacturer" "YAGEO"
			(at 0 0 0)
			(layer "B.Fab")
			(hide yes)
			(effects
				(font
					(size 1 1)
					(thickness 0.15)
				)
				(justify mirror)
			)
		)
		(property "Public" ""
			(at 0 0 0)
			(layer "B.Fab")
			(hide yes)
			(effects
				(font
					(size 1 1)
					(thickness 0.15)
				)
				(justify mirror)
			)
		)
		(property "Val" "10u"
			(at 0 0 0)
			(layer "B.Fab")
			(hide yes)
			(effects
				(font
					(size 1 1)
					(thickness 0.15)
				)
				(justify mirror)
			)
		)
		(property "Voltage" ""
			(at 0 0 0)
			(layer "B.Fab")
			(hide yes)
			(effects
				(font
					(size 1 1)
					(thickness 0.15)
				)
				(justify mirror)
			)
		)
		(sheetname "/Ethernet/")
		(sheetfile "ethernet.kicad_sch")
		(attr smd)
		(fp_rect
			(start -0.925 0.47)
			(end 0.925 -0.47)
			(stroke
				(width 0.05)
				(type default)
			)
			(fill no)
			(layer "B.CrtYd")
		)
		(fp_line
			(start -0.494 -0.248)
			(end -0.494 0.25)
			(stroke
				(width 0.15)
				(type solid)
			)
			(layer "B.Fab")
		)
		(fp_line
			(start -0.494 0.25)
			(end 0.504 0.25)
			(stroke
				(width 0.15)
				(type solid)
			)
			(layer "B.Fab")
		)
		(fp_line
			(start 0.504 -0.248)
			(end -0.494 -0.248)
			(stroke
				(width 0.15)
				(type solid)
			)
			(layer "B.Fab")
		)
		(fp_line
			(start 0.504 0.25)
			(end 0.504 -0.248)
			(stroke
				(width 0.15)
				(type solid)
			)
			(layer "B.Fab")
		)
		(fp_text user "License: Apache-2.0"
			(at -0.939 -5.799 180)
			(layer "B.Fab")
			(effects
				(font
					(size 0.7 0.7)
					(thickness 0.15)
				)
				(justify left bottom mirror)
			)
		)
		(fp_text user "${REFERENCE}"
			(at -0.939 -4.599 180)
			(layer "B.Fab")
			(effects
				(font
					(size 0.7 0.7)
					(thickness 0.15)
				)
				(justify left bottom mirror)
			)
		)
		(fp_text user "Author: Antmicro"
			(at -0.939 -3.399 180)
			(layer "B.Fab")
			(effects
				(font
					(size 0.7 0.7)
					(thickness 0.15)
				)
				(justify left bottom mirror)
			)
		)
		(pad "1" smd roundrect
			(at -0.48 0)
			(size 0.59 0.64)
			(layers "B.Cu" "B.Mask" "B.Paste")
			(roundrect_rratio 0.25)
			(net 417 "GND")
			(pintype "passive")
		)
		(pad "2" smd roundrect
			(at 0.48 0)
			(size 0.59 0.64)
			(layers "B.Cu" "B.Mask" "B.Paste")
			(roundrect_rratio 0.25)
			(net 418 "+2V5")
			(pintype "passive")
		)
	)
	(footprint "antmicro-footprints:R_0402_1005Metric"
		(layer "B.Cu")
		(at 225.6 145.345 180)
		(descr "Resistor SMD 0402")
		(tags "resistor SMD 0402")
		(property "Reference" "R151"
			(at -3.8 -0.405 0)
			(layer "B.SilkS")
			(effects
				(font
					(size 0.7 0.7)
					(thickness 0.15)
				)
				(justify left bottom mirror)
			)
		)
		(property "Value" "R_10k_0402"
			(at -1.011843 -1.772047 0)
			(layer "B.Fab")
			(hide yes)
			(effects
				(font
					(size 0.7 0.7)
					(thickness 0.15)
				)
				(justify left bottom mirror)
			)
		)
		(property "Datasheet" "https://www.bourns.com/docs/product-datasheets/cr.pdf"
			(at 0 0 180)
			(layer "F.Fab")
			(hide yes)
			(effects
				(font
					(size 1.27 1.27)
					(thickness 0.15)
				)
			)
		)
		(property "Description" "SMD Chip Resistor, 10 kohm, ± 1%, 62.5 mW, 0402 [1005 Metric], Thick Film, General Purpose"
			(at 0 0 180)
			(layer "F.Fab")
			(hide yes)
			(effects
				(font
					(size 1.27 1.27)
					(thickness 0.15)
				)
			)
		)
		(property "Author" "Antmicro"
			(at 451.2 290.69 0)
			(layer "B.Fab")
			(hide yes)
			(effects
				(font
					(size 1 1)
					(thickness 0.15)
				)
				(justify mirror)
			)
		)
		(property "License" "Apache-2.0"
			(at 451.2 290.69 0)
			(layer "B.Fab")
			(hide yes)
			(effects
				(font
					(size 1 1)
					(thickness 0.15)
				)
				(justify mirror)
			)
		)
		(property "MPN" "CR0402-FX-1002GLF"
			(at 451.2 290.69 0)
			(layer "B.Fab")
			(hide yes)
			(effects
				(font
					(size 1 1)
					(thickness 0.15)
				)
				(justify mirror)
			)
		)
		(property "Manufacturer" "Bourns"
			(at 451.2 290.69 0)
			(layer "B.Fab")
			(hide yes)
			(effects
				(font
					(size 1 1)
					(thickness 0.15)
				)
				(justify mirror)
			)
		)
		(property "Public" ""
			(at 451.2 290.69 0)
			(layer "B.Fab")
			(hide yes)
			(effects
				(font
					(size 1 1)
					(thickness 0.15)
				)
				(justify mirror)
			)
		)
		(property "Tolerance" "1%"
			(at 451.2 290.69 0)
			(layer "B.Fab")
			(hide yes)
			(effects
				(font
					(size 1 1)
					(thickness 0.15)
				)
				(justify mirror)
			)
		)
		(property "Val" "10k"
			(at 451.2 290.69 0)
			(layer "B.Fab")
			(hide yes)
			(effects
				(font
					(size 1 1)
					(thickness 0.15)
				)
				(justify mirror)
			)
		)
		(sheetname "/WiFi_Bluetooth/")
		(sheetfile "wifi_bt.kicad_sch")
		(attr smd)
		(fp_rect
			(start -0.925 0.47)
			(end 0.925 -0.47)
			(stroke
				(width 0.05)
				(type default)
			)
			(fill no)
			(layer "B.CrtYd")
		)
		(fp_rect
			(start -0.5 0.25)
			(end 0.5 -0.25)
			(stroke
				(width 0.15)
				(type solid)
			)
			(fill no)
			(layer "B.Fab")
		)
		(fp_text user "Author: Antmicro"
			(at -0.95 -4.169 0)
			(layer "B.Fab")
			(effects
				(font
					(size 0.7 0.7)
					(thickness 0.15)
				)
				(justify left bottom mirror)
			)
		)
		(fp_text user "${REFERENCE}"
			(at -0.95 -3.168 0)
			(layer "B.Fab")
			(effects
				(font
					(size 0.7 0.7)
					(thickness 0.15)
				)
				(justify left bottom mirror)
			)
		)
		(fp_text user "License: Apache-2.0"
			(at -0.95 -5.169 0)
			(layer "B.Fab")
			(effects
				(font
					(size 0.7 0.7)
					(thickness 0.15)
				)
				(justify left bottom mirror)
			)
		)
		(pad "1" smd roundrect
			(at -0.48 0 180)
			(size 0.59 0.64)
			(layers "B.Cu" "B.Mask" "B.Paste")
			(roundrect_rratio 0.25)
			(net 417 "GND")
			(pintype "passive")
		)
		(pad "2" smd roundrect
			(at 0.48 0 180)
			(size 0.59 0.64)
			(layers "B.Cu" "B.Mask" "B.Paste")
			(roundrect_rratio 0.25)
			(net 424 "/WiFi_Bluetooth/JTAG_SEL")
			(pintype "passive")
		)
	)
	(footprint "antmicro-footprints:TP_SMD_0.75mm"
		(layer "B.Cu")
		(at 197.75 145.15 180)
		(property "Reference" "TP24"
			(at -2.175 -1.15 135)
			(layer "B.SilkS")
			(hide yes)
			(effects
				(font
					(size 0.7 0.7)
					(thickness 0.15)
				)
				(justify left bottom mirror)
			)
		)
		(property "Value" "TP_0.75mm_SMD"
			(at 0 -1.2 0)
			(layer "B.Fab")
			(hide yes)
			(effects
				(font
					(size 0.7 0.7)
					(thickness 0.15)
				)
				(justify left bottom mirror)
			)
		)
		(property "Description" "SMT test point"
			(at 0 0 0)
			(layer "B.Fab")
			(hide yes)
			(effects
				(font
					(size 1.27 1.27)
					(thickness 0.15)
				)
				(justify mirror)
			)
		)
		(property "MPN" ""
			(at 0 0 0)
			(unlocked yes)
			(layer "B.Fab")
			(hide yes)
			(effects
				(font
					(size 1 1)
					(thickness 0.15)
				)
				(justify mirror)
			)
		)
		(property "Manufacturer" ""
			(at 0 0 0)
			(unlocked yes)
			(layer "B.Fab")
			(hide yes)
			(effects
				(font
					(size 1 1)
					(thickness 0.15)
				)
				(justify mirror)
			)
		)
		(property "Author" "Antmicro"
			(at 0 0 0)
			(unlocked yes)
			(layer "B.Fab")
			(hide yes)
			(effects
				(font
					(size 1 1)
					(thickness 0.15)
				)
				(justify mirror)
			)
		)
		(property "License" "Apache-2.0"
			(at 0 0 0)
			(unlocked yes)
			(layer "B.Fab")
			(hide yes)
			(effects
				(font
					(size 1 1)
					(thickness 0.15)
				)
				(justify mirror)
			)
		)
		(property "Public" "False"
			(at 0 0 0)
			(unlocked yes)
			(layer "B.Fab")
			(hide yes)
			(effects
				(font
					(size 1 1)
					(thickness 0.15)
				)
				(justify mirror)
			)
		)
		(sheetname "/Supply/")
		(sheetfile "supply.kicad_sch")
		(attr exclude_from_pos_files exclude_from_bom)
		(fp_circle
			(center 0 0)
			(end 0.475 0)
			(stroke
				(width 0.05)
				(type default)
			)
			(fill no)
			(layer "B.CrtYd")
		)
		(fp_text user "Author: Antmicro"
			(at -0.4 -3.901 0)
			(layer "B.Fab")
			(effects
				(font
					(size 0.7 0.7)
					(thickness 0.15)
				)
				(justify left bottom mirror)
			)
		)
		(fp_text user "License: Apache-2.0"
			(at -0.4 -5.101 0)
			(layer "B.Fab")
			(effects
				(font
					(size 0.7 0.7)
					(thickness 0.15)
				)
				(justify left bottom mirror)
			)
		)
		(fp_text user "${REFERENCE}"
			(at -0.4 -2.7 0)
			(layer "B.Fab")
			(effects
				(font
					(size 0.7 0.7)
					(thickness 0.15)
				)
				(justify left bottom mirror)
			)
		)
		(pad "1" smd circle
			(at 0 0 180)
			(size 0.75 0.75)
			(layers "B.Cu" "B.Mask")
			(net 90 "+5V")
			(pinfunction "1")
			(pintype "passive")
		)
	)
)
